(kicad_pcb
	(version 20260206)
	(generator "pcbnew")
	(generator_version "10.0")
	(general
		(thickness 1.6)
		(legacy_teardrops no)
	)
	(paper "A4")
	(title_block
		(title "v1-chassis-manager — T6M_CM_d_v01_1031_1645.brd")
		(comment 1 "Open CloudServer (Microsoft) / footprints 2394-2403 of 2512")
	)
	(layers
		(0 "F.Cu" signal "TOP")
		(4 "In1.Cu" signal "GND1")
		(6 "In2.Cu" signal "IN1")
		(8 "In3.Cu" signal "VCC1")
		(10 "In4.Cu" signal "VCC2")
		(12 "In5.Cu" signal "GND2")
		(14 "In6.Cu" signal "IN2")
		(16 "In7.Cu" signal "IN3")
		(18 "In8.Cu" signal "GND3")
		(2 "B.Cu" signal "BOTTOM")
		(9 "F.Adhes" user "F.Adhesive")
		(11 "B.Adhes" user "B.Adhesive")
		(13 "F.Paste" user "Package Geometry/Pastemask Top")
		(15 "B.Paste" user "Package Geometry/Pastemask Bottom")
		(5 "F.SilkS" user "Ref Des/Silkscreen Top")
		(7 "B.SilkS" user "Ref Des/Silkscreen Bottom")
		(1 "F.Mask" user "Board Geometry/Soldermask Top")
		(3 "B.Mask" user "Board Geometry/Soldermask Bottom")
		(17 "Dwgs.User" user "User.Drawings")
		(19 "Cmts.User" user "User.Comments")
		(21 "Eco1.User" user "User.Eco1")
		(23 "Eco2.User" user "User.Eco2")
		(25 "Edge.Cuts" user "Board Geometry/Outline")
		(27 "Margin" user)
		(31 "F.CrtYd" user "Package Geometry/Place Bound Top")
		(29 "B.CrtYd" user "Package Geometry/Place Bound Bottom")
		(35 "F.Fab" user "Ref Des/Assembly Top")
		(33 "B.Fab" user "Ref Des/Assembly Bottom")
	)
	(footprint ""
		(layer "B.Cu")
		(at 121.72061 -37.430456 180)
		(property "Reference" "R1203"
			(at 3.310636 -0.941578 0)
			(unlocked yes)
			(layer "B.SilkS")
			(effects
				(font
					(size 0.7874 0.5842)
					(thickness 0.1524)
				)
				(justify left mirror)
			)
		)
		(property "Value" ""
			(at 0 0 0)
			(layer "B.Fab")
			(effects
				(font
					(size 1.27 1.27)
				)
				(justify mirror)
			)
		)
		(duplicate_pad_numbers_are_jumpers no)
		(fp_line
			(start 0.7874 0.4064)
			(end 0.7874 -0.4064)
			(stroke
				(width 0.1524)
				(type default)
			)
			(layer "B.SilkS")
		)
		(fp_line
			(start 0.7874 -0.4064)
			(end -0.7874 -0.4064)
			(stroke
				(width 0.1524)
				(type default)
			)
			(layer "B.SilkS")
		)
		(fp_line
			(start -0.7874 0.4064)
			(end 0.7874 0.4064)
			(stroke
				(width 0.1524)
				(type default)
			)
			(layer "B.SilkS")
		)
		(fp_line
			(start -0.7874 -0.4064)
			(end -0.7874 0.4064)
			(stroke
				(width 0.1524)
				(type default)
			)
			(layer "B.SilkS")
		)
		(fp_poly
			(pts
				(xy 0.508 0.2794) (xy 0.508 0.2286) (xy 0.635 0.2286) (xy 0.635 -0.254) (xy 0.5334 -0.254) (xy 0.5334 -0.2794)
				(xy -0.5334 -0.2794) (xy -0.5334 -0.254) (xy -0.635 -0.254) (xy -0.635 0.254) (xy -0.5334 0.254)
				(xy -0.5334 0.2794)
			)
			(stroke
				(width 0)
				(type default)
			)
			(fill no)
			(layer "B.CrtYd")
		)
		(pad "1" smd rect
			(at -0.40005 0)
			(size 0.4572 0.508)
			(layers "B.Cu" "B.Mask" "B.Paste")
			(net "SIO_JTAG_CPLD3_TDO")
		)
		(pad "2" smd rect
			(at 0.40005 0)
			(size 0.4572 0.508)
			(layers "B.Cu" "B.Mask" "B.Paste")
			(net "P3V3_NODE1")
		)
	)
	(footprint ""
		(layer "B.Cu")
		(at 88.77935 -74.701654)
		(property "Reference" "R162"
			(at -1.91516 9.822434 0)
			(unlocked yes)
			(layer "B.SilkS")
			(effects
				(font
					(size 0.7874 0.5842)
					(thickness 0.1524)
				)
				(justify left mirror)
			)
		)
		(property "Value" ""
			(at 0 0 0)
			(layer "B.Fab")
			(effects
				(font
					(size 1.27 1.27)
				)
				(justify mirror)
			)
		)
		(duplicate_pad_numbers_are_jumpers no)
		(fp_line
			(start -0.7874 -0.4064)
			(end -0.7874 0.4064)
			(stroke
				(width 0.1524)
				(type default)
			)
			(layer "B.SilkS")
		)
		(fp_line
			(start -0.7874 0.4064)
			(end 0.7874 0.4064)
			(stroke
				(width 0.1524)
				(type default)
			)
			(layer "B.SilkS")
		)
		(fp_line
			(start 0.7874 -0.4064)
			(end -0.7874 -0.4064)
			(stroke
				(width 0.1524)
				(type default)
			)
			(layer "B.SilkS")
		)
		(fp_line
			(start 0.7874 0.4064)
			(end 0.7874 -0.4064)
			(stroke
				(width 0.1524)
				(type default)
			)
			(layer "B.SilkS")
		)
		(fp_poly
			(pts
				(xy 0.508 0.2794) (xy 0.508 0.2286) (xy 0.635 0.2286) (xy 0.635 -0.254) (xy 0.5334 -0.254) (xy 0.5334 -0.2794)
				(xy -0.5334 -0.2794) (xy -0.5334 -0.254) (xy -0.635 -0.254) (xy -0.635 0.254) (xy -0.5334 0.254)
				(xy -0.5334 0.2794)
			)
			(stroke
				(width 0)
				(type default)
			)
			(fill no)
			(layer "B.CrtYd")
		)
		(pad "1" smd rect
			(at -0.40005 0 180)
			(size 0.4572 0.508)
			(layers "B.Cu" "B.Mask" "B.Paste")
			(net "GND")
		)
		(pad "2" smd rect
			(at 0.40005 0 180)
			(size 0.4572 0.508)
			(layers "B.Cu" "B.Mask" "B.Paste")
			(net "PD_CPU_NODE1_HVMGEAR_SEL")
		)
	)
	(footprint ""
		(layer "B.Cu")
		(at 78.83144 -170.473624 180)
		(property "Reference" "R689"
			(at -30.663388 -21.657818 0)
			(unlocked yes)
			(layer "B.SilkS")
			(effects
				(font
					(size 0.7874 0.5842)
					(thickness 0.1524)
				)
				(justify left mirror)
			)
		)
		(property "Value" ""
			(at 0 0 0)
			(layer "B.Fab")
			(effects
				(font
					(size 1.27 1.27)
				)
				(justify mirror)
			)
		)
		(duplicate_pad_numbers_are_jumpers no)
		(fp_line
			(start 0.7874 0.4064)
			(end 0.7874 -0.4064)
			(stroke
				(width 0.1524)
				(type default)
			)
			(layer "B.SilkS")
		)
		(fp_line
			(start 0.7874 -0.4064)
			(end -0.7874 -0.4064)
			(stroke
				(width 0.1524)
				(type default)
			)
			(layer "B.SilkS")
		)
		(fp_line
			(start -0.7874 0.4064)
			(end 0.7874 0.4064)
			(stroke
				(width 0.1524)
				(type default)
			)
			(layer "B.SilkS")
		)
		(fp_line
			(start -0.7874 -0.4064)
			(end -0.7874 0.4064)
			(stroke
				(width 0.1524)
				(type default)
			)
			(layer "B.SilkS")
		)
		(fp_poly
			(pts
				(xy 0.508 0.2794) (xy 0.508 0.2286) (xy 0.635 0.2286) (xy 0.635 -0.254) (xy 0.5334 -0.254) (xy 0.5334 -0.2794)
				(xy -0.5334 -0.2794) (xy -0.5334 -0.254) (xy -0.635 -0.254) (xy -0.635 0.254) (xy -0.5334 0.254)
				(xy -0.5334 0.2794)
			)
			(stroke
				(width 0)
				(type default)
			)
			(fill no)
			(layer "B.CrtYd")
		)
		(pad "1" smd rect
			(at -0.40005 0)
			(size 0.4572 0.508)
			(layers "B.Cu" "B.Mask" "B.Paste")
			(net "T1_NODE1_EN")
		)
		(pad "2" smd rect
			(at 0.40005 0)
			(size 0.4572 0.508)
			(layers "B.Cu" "B.Mask" "B.Paste")
			(net "P5V_NODE1")
		)
	)
	(footprint ""
		(layer "B.Cu")
		(at 75.239372 -80.514698 90)
		(property "Reference" "C86"
			(at -32.158686 -14.55039 270)
			(unlocked yes)
			(layer "B.SilkS")
			(effects
				(font
					(size 0.7874 0.5842)
					(thickness 0.1524)
				)
				(justify left mirror)
			)
		)
		(property "Value" ""
			(at 0 0 90)
			(layer "B.Fab")
			(effects
				(font
					(size 1.27 1.27)
				)
				(justify mirror)
			)
		)
		(duplicate_pad_numbers_are_jumpers no)
		(fp_line
			(start 0.7874 -0.4064)
			(end -0.7874 -0.4064)
			(stroke
				(width 0.1524)
				(type default)
			)
			(layer "B.SilkS")
		)
		(fp_line
			(start -0.7874 -0.4064)
			(end -0.7874 0.4064)
			(stroke
				(width 0.1524)
				(type default)
			)
			(layer "B.SilkS")
		)
		(fp_line
			(start 0 0.381)
			(end 0 -0.381)
			(stroke
				(width 0.1524)
				(type default)
			)
			(layer "B.SilkS")
		)
		(fp_line
			(start 0.7874 0.4064)
			(end 0.7874 -0.4064)
			(stroke
				(width 0.1524)
				(type default)
			)
			(layer "B.SilkS")
		)
		(fp_line
			(start -0.7874 0.4064)
			(end 0.7874 0.4064)
			(stroke
				(width 0.1524)
				(type default)
			)
			(layer "B.SilkS")
		)
		(fp_poly
			(pts
				(xy 0.5334 0.254) (xy 0.635 0.254) (xy 0.635 0.2286) (xy 0.635 -0.254) (xy 0.5334 -0.254) (xy 0.5334 -0.2794)
				(xy -0.5334 -0.2794) (xy -0.5334 -0.254) (xy -0.635 -0.254) (xy -0.635 0.254) (xy -0.5334 0.254)
				(xy -0.5334 0.2794) (xy 0.508 0.2794) (xy 0.5334 0.2794)
			)
			(stroke
				(width 0)
				(type default)
			)
			(fill no)
			(layer "B.CrtYd")
		)
		(pad "1" smd rect
			(at -0.40005 0 270)
			(size 0.4572 0.508)
			(layers "B.Cu" "B.Mask" "B.Paste")
			(net "PV_VCCP_NODE1")
		)
		(pad "2" smd rect
			(at 0.40005 0 270)
			(size 0.4572 0.508)
			(layers "B.Cu" "B.Mask" "B.Paste")
			(net "GND")
		)
	)
	(footprint ""
		(layer "B.Cu")
		(at 125.892052 -147.19935 180)
		(property "Reference" "C862"
			(at 3.002534 4.472432 0)
			(unlocked yes)
			(layer "B.SilkS")
			(effects
				(font
					(size 0.7874 0.5842)
					(thickness 0.1524)
				)
				(justify left mirror)
			)
		)
		(property "Value" ""
			(at 0 0 0)
			(layer "B.Fab")
			(effects
				(font
					(size 1.27 1.27)
				)
				(justify mirror)
			)
		)
		(duplicate_pad_numbers_are_jumpers no)
		(fp_line
			(start 0.7874 0.4064)
			(end 0.7874 -0.4064)
			(stroke
				(width 0.1524)
				(type default)
			)
			(layer "B.SilkS")
		)
		(fp_line
			(start 0.7874 -0.4064)
			(end -0.7874 -0.4064)
			(stroke
				(width 0.1524)
				(type default)
			)
			(layer "B.SilkS")
		)
		(fp_line
			(start 0 0.381)
			(end 0 -0.381)
			(stroke
				(width 0.1524)
				(type default)
			)
			(layer "B.SilkS")
		)
		(fp_line
			(start -0.7874 0.4064)
			(end 0.7874 0.4064)
			(stroke
				(width 0.1524)
				(type default)
			)
			(layer "B.SilkS")
		)
		(fp_line
			(start -0.7874 -0.4064)
			(end -0.7874 0.4064)
			(stroke
				(width 0.1524)
				(type default)
			)
			(layer "B.SilkS")
		)
		(fp_poly
			(pts
				(xy 0.5334 0.254) (xy 0.635 0.254) (xy 0.635 0.2286) (xy 0.635 -0.254) (xy 0.5334 -0.254) (xy 0.5334 -0.2794)
				(xy -0.5334 -0.2794) (xy -0.5334 -0.254) (xy -0.635 -0.254) (xy -0.635 0.254) (xy -0.5334 0.254)
				(xy -0.5334 0.2794) (xy 0.508 0.2794) (xy 0.5334 0.2794)
			)
			(stroke
				(width 0)
				(type default)
			)
			(fill no)
			(layer "B.CrtYd")
		)
		(pad "1" smd rect
			(at -0.40005 0)
			(size 0.4572 0.508)
			(layers "B.Cu" "B.Mask" "B.Paste")
			(net "P1V0_NODE1")
		)
		(pad "2" smd rect
			(at 0.40005 0)
			(size 0.4572 0.508)
			(layers "B.Cu" "B.Mask" "B.Paste")
			(net "GND")
		)
	)
	(footprint ""
		(layer "B.Cu")
		(at 141.005052 -143.00835 -90)
		(property "Reference" "C889"
			(at 0.15875 1.207516 0)
			(unlocked yes)
			(layer "B.SilkS")
			(effects
				(font
					(size 0.7874 0.5842)
					(thickness 0.1524)
				)
				(justify left mirror)
			)
		)
		(property "Value" ""
			(at 0 0 90)
			(layer "B.Fab")
			(effects
				(font
					(size 1.27 1.27)
				)
				(justify mirror)
			)
		)
		(duplicate_pad_numbers_are_jumpers no)
		(fp_line
			(start -0.7874 0.4064)
			(end 0.7874 0.4064)
			(stroke
				(width 0.1524)
				(type default)
			)
			(layer "B.SilkS")
		)
		(fp_line
			(start 0.7874 0.4064)
			(end 0.7874 -0.4064)
			(stroke
				(width 0.1524)
				(type default)
			)
			(layer "B.SilkS")
		)
		(fp_line
			(start 0 0.381)
			(end 0 -0.381)
			(stroke
				(width 0.1524)
				(type default)
			)
			(layer "B.SilkS")
		)
		(fp_line
			(start -0.7874 -0.4064)
			(end -0.7874 0.4064)
			(stroke
				(width 0.1524)
				(type default)
			)
			(layer "B.SilkS")
		)
		(fp_line
			(start 0.7874 -0.4064)
			(end -0.7874 -0.4064)
			(stroke
				(width 0.1524)
				(type default)
			)
			(layer "B.SilkS")
		)
		(fp_poly
			(pts
				(xy 0.5334 0.254) (xy 0.635 0.254) (xy 0.635 0.2286) (xy 0.635 -0.254) (xy 0.5334 -0.254) (xy 0.5334 -0.2794)
				(xy -0.5334 -0.2794) (xy -0.5334 -0.254) (xy -0.635 -0.254) (xy -0.635 0.254) (xy -0.5334 0.254)
				(xy -0.5334 0.2794) (xy 0.508 0.2794) (xy 0.5334 0.2794)
			)
			(stroke
				(width 0)
				(type default)
			)
			(fill no)
			(layer "B.CrtYd")
		)
		(pad "1" smd rect
			(at -0.40005 0 90)
			(size 0.4572 0.508)
			(layers "B.Cu" "B.Mask" "B.Paste")
			(net "P1V0_NODE1")
		)
		(pad "2" smd rect
			(at 0.40005 0 90)
			(size 0.4572 0.508)
			(layers "B.Cu" "B.Mask" "B.Paste")
			(net "GND")
		)
	)
	(footprint ""
		(layer "B.Cu")
		(at 56.202326 -144.809464 180)
		(property "Reference" "R670"
			(at 0.974852 -2.773934 0)
			(unlocked yes)
			(layer "B.SilkS")
			(effects
				(font
					(size 0.7874 0.5842)
					(thickness 0.1524)
				)
				(justify left mirror)
			)
		)
		(property "Value" ""
			(at 0 0 0)
			(layer "B.Fab")
			(effects
				(font
					(size 1.27 1.27)
				)
				(justify mirror)
			)
		)
		(duplicate_pad_numbers_are_jumpers no)
		(fp_line
			(start 0.7874 0.4064)
			(end 0.7874 -0.4064)
			(stroke
				(width 0.1524)
				(type default)
			)
			(layer "B.SilkS")
		)
		(fp_line
			(start 0.7874 -0.4064)
			(end -0.7874 -0.4064)
			(stroke
				(width 0.1524)
				(type default)
			)
			(layer "B.SilkS")
		)
		(fp_line
			(start -0.7874 0.4064)
			(end 0.7874 0.4064)
			(stroke
				(width 0.1524)
				(type default)
			)
			(layer "B.SilkS")
		)
		(fp_line
			(start -0.7874 -0.4064)
			(end -0.7874 0.4064)
			(stroke
				(width 0.1524)
				(type default)
			)
			(layer "B.SilkS")
		)
		(fp_poly
			(pts
				(xy 0.508 0.2794) (xy 0.508 0.2286) (xy 0.635 0.2286) (xy 0.635 -0.254) (xy 0.5334 -0.254) (xy 0.5334 -0.2794)
				(xy -0.5334 -0.2794) (xy -0.5334 -0.254) (xy -0.635 -0.254) (xy -0.635 0.254) (xy -0.5334 0.254)
				(xy -0.5334 0.2794)
			)
			(stroke
				(width 0)
				(type default)
			)
			(fill no)
			(layer "B.CrtYd")
		)
		(pad "1" smd rect
			(at -0.40005 0)
			(size 0.4572 0.508)
			(layers "B.Cu" "B.Mask" "B.Paste")
			(net "BMC_NODE1_GFX_HSYNC_R")
		)
		(pad "2" smd rect
			(at 0.40005 0)
			(size 0.4572 0.508)
			(layers "B.Cu" "B.Mask" "B.Paste")
			(net "BMC_NODE1_GFX_HSYNC")
		)
	)
	(footprint ""
		(layer "B.Cu")
		(at 54.101492 -132.452618 180)
		(property "Reference" "C204"
			(at -0.447548 0.951992 0)
			(unlocked yes)
			(layer "B.SilkS")
			(effects
				(font
					(size 0.7874 0.5842)
					(thickness 0.1524)
				)
				(justify left mirror)
			)
		)
		(property "Value" ""
			(at 0 0 0)
			(layer "B.Fab")
			(effects
				(font
					(size 1.27 1.27)
				)
				(justify mirror)
			)
		)
		(duplicate_pad_numbers_are_jumpers no)
		(fp_line
			(start 0.7874 0.4064)
			(end 0.7874 -0.4064)
			(stroke
				(width 0.1524)
				(type default)
			)
			(layer "B.SilkS")
		)
		(fp_line
			(start 0.7874 -0.4064)
			(end -0.7874 -0.4064)
			(stroke
				(width 0.1524)
				(type default)
			)
			(layer "B.SilkS")
		)
		(fp_line
			(start 0 0.381)
			(end 0 -0.381)
			(stroke
				(width 0.1524)
				(type default)
			)
			(layer "B.SilkS")
		)
		(fp_line
			(start -0.7874 0.4064)
			(end 0.7874 0.4064)
			(stroke
				(width 0.1524)
				(type default)
			)
			(layer "B.SilkS")
		)
		(fp_line
			(start -0.7874 -0.4064)
			(end -0.7874 0.4064)
			(stroke
				(width 0.1524)
				(type default)
			)
			(layer "B.SilkS")
		)
		(fp_poly
			(pts
				(xy 0.5334 0.254) (xy 0.635 0.254) (xy 0.635 0.2286) (xy 0.635 -0.254) (xy 0.5334 -0.254) (xy 0.5334 -0.2794)
				(xy -0.5334 -0.2794) (xy -0.5334 -0.254) (xy -0.635 -0.254) (xy -0.635 0.254) (xy -0.5334 0.254)
				(xy -0.5334 0.2794) (xy 0.508 0.2794) (xy 0.5334 0.2794)
			)
			(stroke
				(width 0)
				(type default)
			)
			(fill no)
			(layer "B.CrtYd")
		)
		(pad "1" smd rect
			(at -0.40005 0)
			(size 0.4572 0.508)
			(layers "B.Cu" "B.Mask" "B.Paste")
			(net "P0V75_BMC_VTTREF_NODE1")
		)
		(pad "2" smd rect
			(at 0.40005 0)
			(size 0.4572 0.508)
			(layers "B.Cu" "B.Mask" "B.Paste")
			(net "GND")
		)
	)
	(footprint ""
		(layer "B.Cu")
		(at 131.311904 -39.064438 180)
		(property "Reference" "R1081"
			(at -0.412496 2.463292 0)
			(unlocked yes)
			(layer "B.SilkS")
			(effects
				(font
					(size 0.7874 0.5842)
					(thickness 0.1524)
				)
				(justify left mirror)
			)
		)
		(property "Value" ""
			(at 0 0 0)
			(layer "B.Fab")
			(effects
				(font
					(size 1.27 1.27)
				)
				(justify mirror)
			)
		)
		(duplicate_pad_numbers_are_jumpers no)
		(fp_line
			(start 0.7874 0.4064)
			(end 0.7874 -0.4064)
			(stroke
				(width 0.1524)
				(type default)
			)
			(layer "B.SilkS")
		)
		(fp_line
			(start 0.7874 -0.4064)
			(end -0.7874 -0.4064)
			(stroke
				(width 0.1524)
				(type default)
			)
			(layer "B.SilkS")
		)
		(fp_line
			(start -0.7874 0.4064)
			(end 0.7874 0.4064)
			(stroke
				(width 0.1524)
				(type default)
			)
			(layer "B.SilkS")
		)
		(fp_line
			(start -0.7874 -0.4064)
			(end -0.7874 0.4064)
			(stroke
				(width 0.1524)
				(type default)
			)
			(layer "B.SilkS")
		)
		(fp_poly
			(pts
				(xy 0.508 0.2794) (xy 0.508 0.2286) (xy 0.635 0.2286) (xy 0.635 -0.254) (xy 0.5334 -0.254) (xy 0.5334 -0.2794)
				(xy -0.5334 -0.2794) (xy -0.5334 -0.254) (xy -0.635 -0.254) (xy -0.635 0.254) (xy -0.5334 0.254)
				(xy -0.5334 0.2794)
			)
			(stroke
				(width 0)
				(type default)
			)
			(fill no)
			(layer "B.CrtYd")
		)
		(pad "1" smd rect
			(at -0.40005 0)
			(size 0.4572 0.508)
			(layers "B.Cu" "B.Mask" "B.Paste")
			(net "SIO_JTAG_CPLD2_TDI")
		)
		(pad "2" smd rect
			(at 0.40005 0)
			(size 0.4572 0.508)
			(layers "B.Cu" "B.Mask" "B.Paste")
			(net "JTAG_CPLD2_TDI")
		)
	)
	(footprint ""
		(layer "B.Cu")
		(at 65.38976 -185.205624 90)
		(property "Reference" "R862"
			(at 4.15163 0.217678 270)
			(unlocked yes)
			(layer "B.SilkS")
			(effects
				(font
					(size 0.7874 0.5842)
					(thickness 0.1524)
				)
				(justify left mirror)
			)
		)
		(property "Value" ""
			(at 0 0 90)
			(layer "B.Fab")
			(effects
				(font
					(size 1.27 1.27)
				)
				(justify mirror)
			)
		)
		(duplicate_pad_numbers_are_jumpers no)
		(fp_line
			(start 0.7874 -0.406146)
			(end -0.7874 -0.406146)
			(stroke
				(width 0.1524)
				(type default)
			)
			(layer "B.SilkS")
		)
		(fp_line
			(start -0.7874 -0.406146)
			(end -0.7874 0.406146)
			(stroke
				(width 0.1524)
				(type default)
			)
			(layer "B.SilkS")
		)
		(fp_line
			(start 0.7874 0.406146)
			(end 0.7874 -0.406146)
			(stroke
				(width 0.1524)
				(type default)
			)
			(layer "B.SilkS")
		)
		(fp_line
			(start -0.7874 0.406146)
			(end 0.7874 0.406146)
			(stroke
				(width 0.1524)
				(type default)
			)
			(layer "B.SilkS")
		)
		(fp_poly
			(pts
				(xy 0.508 0.2794) (xy 0.508 0.2286) (xy 0.635 0.2286) (xy 0.635 -0.254) (xy 0.5334 -0.254) (xy 0.5334 -0.2794)
				(xy -0.5334 -0.2794) (xy -0.5334 -0.254) (xy -0.635 -0.254) (xy -0.635 0.254) (xy -0.5334 0.254)
				(xy -0.5334 0.2794)
			)
			(stroke
				(width 0)
				(type default)
			)
			(fill no)
			(layer "B.CrtYd")
		)
		(pad "1" smd rect
			(at -0.40005 0 270)
			(size 0.4572 0.508)
			(layers "B.Cu" "B.Mask" "B.Paste")
			(net "T1_NODE2_EN")
		)
		(pad "2" smd rect
			(at 0.40005 0 270)
			(size 0.4572 0.508)
			(layers "B.Cu" "B.Mask" "B.Paste")
			(net "T1_NODE2_EN_R")
		)
	)
)
